(kicad_pcb
	(version 20260206)
	(generator "pcbnew")
	(generator_version "10.0")
	(general
		(thickness 1.6)
		(legacy_teardrops no)
	)
	(paper "A4")
	(title_block
		(title "04192023_DAF0TMB3IC0_F0TG_MB_C_brd_V02_OCP.brd")
		(comment 1 "Grand Teton / footprints 3116-3119 of 8354")
	)
	(layers
		(0 "F.Cu" signal "TOP")
		(4 "In1.Cu" signal "GND")
		(6 "In2.Cu" signal "IN1")
		(8 "In3.Cu" signal "GND1")
		(10 "In4.Cu" signal "IN2")
		(12 "In5.Cu" signal "GND2")
		(14 "In6.Cu" signal "IN3")
		(16 "In7.Cu" signal "GND3")
		(18 "In8.Cu" signal "VCC")
		(20 "In9.Cu" signal "VCC1")
		(22 "In10.Cu" signal "GND4")
		(24 "In11.Cu" signal "IN4")
		(26 "In12.Cu" signal "GND5")
		(28 "In13.Cu" signal "IN5")
		(30 "In14.Cu" signal "GND6")
		(32 "In15.Cu" signal "IN6")
		(34 "In16.Cu" signal "GND7")
		(2 "B.Cu" signal "BOTTOM")
		(9 "F.Adhes" user "F.Adhesive")
		(11 "B.Adhes" user "B.Adhesive")
		(13 "F.Paste" user "Package Geometry/Pastemask Top")
		(15 "B.Paste" user "Package Geometry/Pastemask Bottom")
		(5 "F.SilkS" user "Ref Des/Silkscreen Top")
		(7 "B.SilkS" user "Ref Des/Silkscreen Bottom")
		(1 "F.Mask" user "Board Geometry/Soldermask Top")
		(3 "B.Mask" user "Board Geometry/Soldermask Bottom")
		(17 "Dwgs.User" user "User.Drawings")
		(19 "Cmts.User" user "User.Comments")
		(21 "Eco1.User" user "User.Eco1")
		(23 "Eco2.User" user "User.Eco2")
		(25 "Edge.Cuts" user "Board Geometry/Outline")
		(27 "Margin" user)
		(31 "F.CrtYd" user "Package Geometry/Place Bound Top")
		(29 "B.CrtYd" user "Package Geometry/Place Bound Bottom")
		(35 "F.Fab" user "Ref Des/Assembly Top")
		(33 "B.Fab" user "Ref Des/Assembly Bottom")
	)
	(footprint ""
		(layer "F.Cu")
		(at 413.270192 -140.783056)
		(property "Reference" "U326"
			(at 4.306062 0.730758 90)
			(unlocked yes)
			(layer "F.SilkS")
			(effects
				(font
					(size 0.7874 0.5842)
					(thickness 0.1524)
				)
				(justify left)
			)
		)
		(property "Value" ""
			(at 0 0 0)
			(layer "F.Fab")
			(effects
				(font
					(size 1.27 1.27)
				)
			)
		)
		(duplicate_pad_numbers_are_jumpers no)
		(fp_line
			(start -1.549908 -2.050034)
			(end -1.549908 -1.9812)
			(stroke
				(width 0.1524)
				(type default)
			)
			(layer "F.SilkS")
		)
		(fp_line
			(start -1.549908 1.9812)
			(end -1.549908 2.050034)
			(stroke
				(width 0.1524)
				(type default)
			)
			(layer "F.SilkS")
		)
		(fp_line
			(start -1.549908 2.050034)
			(end -0.5842 2.050034)
			(stroke
				(width 0.1524)
				(type default)
			)
			(layer "F.SilkS")
		)
		(fp_line
			(start -0.5842 -2.050034)
			(end -1.549908 -2.050034)
			(stroke
				(width 0.1524)
				(type default)
			)
			(layer "F.SilkS")
		)
		(fp_line
			(start 0 2.050034)
			(end 1.549908 2.050034)
			(stroke
				(width 0.1524)
				(type default)
			)
			(layer "F.SilkS")
		)
		(fp_line
			(start 1.549908 -2.050034)
			(end 0.5842 -2.050034)
			(stroke
				(width 0.1524)
				(type default)
			)
			(layer "F.SilkS")
		)
		(fp_line
			(start 1.549908 -1.9812)
			(end 1.549908 -2.050034)
			(stroke
				(width 0.1524)
				(type default)
			)
			(layer "F.SilkS")
		)
		(fp_line
			(start 1.549908 2.050034)
			(end 1.549908 1.9304)
			(stroke
				(width 0.1524)
				(type default)
			)
			(layer "F.SilkS")
		)
		(fp_poly
			(pts
				(xy -3.364738 -3.2004) (xy -4.083304 -2.482088) (xy -3.005582 -2.122678)
			)
			(stroke
				(width 0)
				(type default)
			)
			(fill yes)
			(layer "F.SilkS")
		)
		(fp_line
			(start -1.549908 -2.050034)
			(end -1.549908 2.050034)
			(stroke
				(width 0.1)
				(type default)
			)
			(layer "F.Fab")
		)
		(fp_line
			(start -1.549908 2.050034)
			(end 1.549908 2.050034)
			(stroke
				(width 0.1)
				(type default)
			)
			(layer "F.Fab")
		)
		(fp_line
			(start 1.549908 -2.050034)
			(end -1.549908 -2.050034)
			(stroke
				(width 0.1)
				(type default)
			)
			(layer "F.Fab")
		)
		(fp_line
			(start 1.549908 2.050034)
			(end 1.549908 -2.050034)
			(stroke
				(width 0.1)
				(type default)
			)
			(layer "F.Fab")
		)
		(fp_poly
			(pts
				(xy -2.9464 -2.208022) (xy -2.9464 -1.192022) (xy -1.9304 -1.700022)
			)
			(stroke
				(width 0)
				(type default)
			)
			(fill yes)
			(layer "F.Fab")
		)
		(pad "1" smd circle
			(at -1.35001 -1.700022)
			(size 0 0)
			(layers "F.Cu" "F.Mask" "F.Paste")
			(net "SW_P5V_AUX_BST")
		)
		(pad "2" smd rect
			(at -1.400048 -1.199896 90)
			(size 0.1778 0.8128)
			(layers "F.Cu" "F.Mask" "F.Paste")
			(net "GND")
		)
		(pad "3" smd rect
			(at -1.400048 -0.8001 90)
			(size 0.1778 0.8128)
			(layers "F.Cu" "F.Mask" "F.Paste")
			(net "P5V_AUX_CS")
		)
		(pad "4" smd rect
			(at -1.400048 -0.40005 90)
			(size 0.1778 0.8128)
			(layers "F.Cu" "F.Mask" "F.Paste")
			(net "P5V_AUX_MODE")
		)
		(pad "5" smd rect
			(at -1.400048 0 90)
			(size 0.1778 0.8128)
			(layers "F.Cu" "F.Mask" "F.Paste")
			(net "P5V_AUX_REF")
		)
		(pad "6" smd rect
			(at -1.400048 0.40005 90)
			(size 0.1778 0.8128)
			(layers "F.Cu" "F.Mask" "F.Paste")
			(net "GND")
		)
		(pad "7" smd rect
			(at -1.400048 0.8001 90)
			(size 0.1778 0.8128)
			(layers "F.Cu" "F.Mask" "F.Paste")
			(net "P5V_AUX_FB")
		)
		(pad "8" smd rect
			(at -1.400048 1.199896 90)
			(size 0.1778 0.8128)
			(layers "F.Cu" "F.Mask" "F.Paste")
			(net "P5V_AUX_EN")
		)
		(pad "9" smd rect
			(at -1.400048 1.700022 90)
			(size 0.3048 0.8128)
			(layers "F.Cu" "F.Mask" "F.Paste")
			(net "PWRGD_P5V_AUX_R")
		)
		(pad "10" smd rect
			(at -0.299974 1.299972)
			(size 0.3048 2.0066)
			(layers "F.Cu" "F.Mask" "F.Paste")
			(net "SW_P5V_AUX_FLT")
		)
		(pad "11_18" smd circle
			(at 1.175004 0.275082)
			(size 0 0)
			(layers "F.Cu" "F.Mask" "F.Paste")
			(net "GND")
		)
		(pad "19" smd rect
			(at 1.400048 -1.700022 270)
			(size 0.3048 0.8128)
			(layers "F.Cu" "F.Mask" "F.Paste")
			(net "P5V_AUX_VCC")
		)
		(pad "20" smd rect
			(at 0.299974 -1.299972)
			(size 0.3048 2.0066)
			(layers "F.Cu" "F.Mask" "F.Paste")
			(net "SW_P5V_AUX_SW")
		)
		(pad "21" smd rect
			(at -0.299974 -1.299972)
			(size 0.3048 2.0066)
			(layers "F.Cu" "F.Mask" "F.Paste")
			(net "SW_P5V_AUX_FLT")
		)
	)
	(footprint ""
		(layer "F.Cu")
		(at 124.323348 -174.509684 180)
		(property "Reference" "PL36"
			(at -0.772668 6.156198 0)
			(unlocked yes)
			(layer "F.SilkS")
			(effects
				(font
					(size 0.7874 0.5842)
					(thickness 0.1524)
				)
				(justify left)
			)
		)
		(property "Value" ""
			(at 0 0 180)
			(layer "F.Fab")
			(effects
				(font
					(size 1.27 1.27)
				)
			)
		)
		(duplicate_pad_numbers_are_jumpers no)
		(fp_line
			(start 3.750056 5.500116)
			(end 3.750056 -5.500116)
			(stroke
				(width 0.1524)
				(type default)
			)
			(layer "F.SilkS")
		)
		(fp_line
			(start 3.750056 -5.500116)
			(end 2.393442 -5.500116)
			(stroke
				(width 0.1524)
				(type default)
			)
			(layer "F.SilkS")
		)
		(fp_line
			(start 2.393442 5.500116)
			(end 3.750056 5.500116)
			(stroke
				(width 0.1524)
				(type default)
			)
			(layer "F.SilkS")
		)
		(fp_line
			(start -2.393442 5.500116)
			(end -3.750056 5.500116)
			(stroke
				(width 0.1524)
				(type default)
			)
			(layer "F.SilkS")
		)
		(fp_line
			(start -3.750056 5.500116)
			(end -3.750056 -5.500116)
			(stroke
				(width 0.1524)
				(type default)
			)
			(layer "F.SilkS")
		)
		(fp_line
			(start -3.750056 -5.500116)
			(end -2.393442 -5.500116)
			(stroke
				(width 0.1524)
				(type default)
			)
			(layer "F.SilkS")
		)
		(fp_poly
			(pts
				(xy -3.9116 -4.249928) (xy -4.3434 -4.034028) (xy -4.3434 -4.465828)
			)
			(stroke
				(width 0)
				(type default)
			)
			(fill yes)
			(layer "F.SilkS")
		)
		(fp_line
			(start 3.750056 5.500116)
			(end 3.750056 -5.500116)
			(stroke
				(width 0.1)
				(type default)
			)
			(layer "F.Fab")
		)
		(fp_line
			(start 3.750056 -5.500116)
			(end -3.750056 -5.500116)
			(stroke
				(width 0.1)
				(type default)
			)
			(layer "F.Fab")
		)
		(fp_line
			(start -3.750056 5.500116)
			(end 3.750056 5.500116)
			(stroke
				(width 0.1)
				(type default)
			)
			(layer "F.Fab")
		)
		(fp_line
			(start -3.750056 -5.500116)
			(end -3.750056 5.500116)
			(stroke
				(width 0.1)
				(type default)
			)
			(layer "F.Fab")
		)
		(fp_poly
			(pts
				(xy -4.9276 -4.757928) (xy -4.9276 -3.741928) (xy -3.9116 -4.249928)
			)
			(stroke
				(width 0)
				(type default)
			)
			(fill yes)
			(layer "F.Fab")
		)
		(pad "1" smd rect
			(at 0 -4.249928 90)
			(size 2.413 4.5212)
			(layers "F.Cu" "F.Mask" "F.Paste")
			(net "SW_PVDDCR_SOC_P1_SW2")
		)
		(pad "2" smd rect
			(at 0 -1.175004 90)
			(size 1.3716 4.5212)
			(layers "F.Cu" "F.Mask" "F.Paste")
			(net "IND_SOC_P1_CPL3")
		)
		(pad "3" smd rect
			(at 0 1.175004 90)
			(size 1.3716 4.5212)
			(layers "F.Cu" "F.Mask" "F.Paste")
			(net "IND_SOC_P1_CPL2")
		)
		(pad "4" smd rect
			(at 0 4.249928 90)
			(size 2.413 4.5212)
			(layers "F.Cu" "F.Mask" "F.Paste")
			(net "PVDDCR_SOC_P1")
		)
	)
	(footprint ""
		(layer "F.Cu")
		(at 182.919878 -351.295462)
		(property "Reference" "PU44"
			(at -5.9436 -7.47141 0)
			(unlocked yes)
			(layer "F.SilkS")
			(effects
				(font
					(size 0.7874 0.5842)
					(thickness 0.1524)
				)
				(justify left)
			)
		)
		(property "Value" ""
			(at 0 0 0)
			(layer "F.Fab")
			(effects
				(font
					(size 1.27 1.27)
				)
			)
		)
		(duplicate_pad_numbers_are_jumpers no)
		(fp_line
			(start -2.500122 -2.999994)
			(end -2.24409 -2.999994)
			(stroke
				(width 0.1524)
				(type default)
			)
			(layer "F.SilkS")
		)
		(fp_line
			(start -2.500122 -2.529078)
			(end -2.500122 -2.999994)
			(stroke
				(width 0.1524)
				(type default)
			)
			(layer "F.SilkS")
		)
		(fp_line
			(start -2.500122 0.6604)
			(end -2.500122 0.229108)
			(stroke
				(width 0.1524)
				(type default)
			)
			(layer "F.SilkS")
		)
		(fp_line
			(start -2.500122 2.999994)
			(end -2.500122 2.339594)
			(stroke
				(width 0.1524)
				(type default)
			)
			(layer "F.SilkS")
		)
		(fp_line
			(start -2.2987 2.999994)
			(end -2.500122 2.999994)
			(stroke
				(width 0.1524)
				(type default)
			)
			(layer "F.SilkS")
		)
		(fp_line
			(start 2.31394 -2.999994)
			(end 2.500122 -2.999994)
			(stroke
				(width 0.1524)
				(type default)
			)
			(layer "F.SilkS")
		)
		(fp_line
			(start 2.500122 -2.999994)
			(end 2.500122 -2.44348)
			(stroke
				(width 0.1524)
				(type default)
			)
			(layer "F.SilkS")
		)
		(fp_line
			(start 2.500122 2.339594)
			(end 2.500122 2.999994)
			(stroke
				(width 0.1524)
				(type default)
			)
			(layer "F.SilkS")
		)
		(fp_line
			(start 2.500122 2.999994)
			(end 2.2987 2.999994)
			(stroke
				(width 0.1524)
				(type default)
			)
			(layer "F.SilkS")
		)
		(fp_poly
			(pts
				(xy -2.732278 -2.41681) (xy -3.405886 -2.641346) (xy -2.956814 -3.090418)
			)
			(stroke
				(width 0)
				(type default)
			)
			(fill yes)
			(layer "F.SilkS")
		)
		(fp_line
			(start -2.500122 -2.999994)
			(end 2.500122 -2.999994)
			(stroke
				(width 0.1)
				(type default)
			)
			(layer "F.Fab")
		)
		(fp_line
			(start -2.500122 2.999994)
			(end -2.500122 -2.999994)
			(stroke
				(width 0.1)
				(type default)
			)
			(layer "F.Fab")
		)
		(fp_line
			(start 2.500122 -2.999994)
			(end 2.500122 2.999994)
			(stroke
				(width 0.1)
				(type default)
			)
			(layer "F.Fab")
		)
		(fp_line
			(start 2.500122 2.999994)
			(end -2.500122 2.999994)
			(stroke
				(width 0.1)
				(type default)
			)
			(layer "F.Fab")
		)
		(fp_poly
			(pts
				(xy -4.218432 -2.783078) (xy -4.218432 -1.767078) (xy -3.202432 -2.275078)
			)
			(stroke
				(width 0)
				(type default)
			)
			(fill yes)
			(layer "F.Fab")
		)
		(pad "1" smd rect
			(at -2.400046 -2.275078 90)
			(size 0.2286 0.6096)
			(layers "F.Cu" "F.Mask" "F.Paste")
			(net "PVDD11_S3_P1_VOS1")
		)
		(pad "2" smd rect
			(at -2.400046 -1.82499 90)
			(size 0.2286 0.6096)
			(layers "F.Cu" "F.Mask" "F.Paste")
			(net "GND")
		)
		(pad "3" smd rect
			(at -2.400046 -1.374902 90)
			(size 0.2286 0.6096)
			(layers "F.Cu" "F.Mask" "F.Paste")
			(net "PVDD11_S3_P1_VCC1")
		)
		(pad "4" smd rect
			(at -2.400046 -0.925068 90)
			(size 0.2286 0.6096)
			(layers "F.Cu" "F.Mask" "F.Paste")
			(net "PVDD11_S3_P1_PVCC")
		)
		(pad "5" smd rect
			(at -2.400046 -0.47498 90)
			(size 0.2286 0.6096)
			(layers "F.Cu" "F.Mask" "F.Paste")
			(net "GND")
		)
		(pad "6" smd rect
			(at -2.400046 -0.024892 90)
			(size 0.2286 0.6096)
			(layers "F.Cu" "F.Mask" "F.Paste")
			(net "NC_PVDD11_S3_P1_GL1_1")
		)
		(pad "7_9-20_24" smd circle
			(at 0 1.150112 90)
			(size 0 0)
			(layers "F.Cu" "F.Mask" "F.Paste")
			(net "GND")
		)
		(pad "10_19" smd rect
			(at 0 2.899918 90)
			(size 0.6096 4.318)
			(layers "F.Cu" "F.Mask" "F.Paste")
			(net "SW_PVDD11_S3_P1_SW1")
		)
		(pad "25_29" smd rect
			(at 1.549908 -1.279906 270)
			(size 2.0574 2.3114)
			(layers "F.Cu" "F.Mask" "F.Paste")
			(net "SW_P12V_AUX_PVDD11_S3_P1_FLT")
		)
		(pad "30" smd rect
			(at 2.05994 -2.899918)
			(size 0.2286 0.6096)
			(layers "F.Cu" "F.Mask" "F.Paste")
			(net "SW_P12V_AUX_PVDD11_S3_P1_FLT")
		)
		(pad "31" smd rect
			(at 1.610106 -2.899918)
			(size 0.2286 0.6096)
			(layers "F.Cu" "F.Mask" "F.Paste")
			(net "NC_PVDD11_S3_P1_DNC1")
		)
		(pad "32" smd rect
			(at 1.160018 -2.899918)
			(size 0.2286 0.6096)
			(layers "F.Cu" "F.Mask" "F.Paste")
			(net "SW_PVDD11_S3_P1_PH1")
		)
		(pad "33" smd rect
			(at 0.70993 -2.899918)
			(size 0.2286 0.6096)
			(layers "F.Cu" "F.Mask" "F.Paste")
			(net "SW_PVDD11_S3_P1_BOOT1")
		)
		(pad "34" smd rect
			(at 0.260096 -2.899918)
			(size 0.2286 0.6096)
			(layers "F.Cu" "F.Mask" "F.Paste")
			(net "PVDD11_S3_P1_PWM1")
		)
		(pad "35" smd rect
			(at -0.189992 -2.899918)
			(size 0.2286 0.6096)
			(layers "F.Cu" "F.Mask" "F.Paste")
			(net "PVDD11_S3_P1_VCC1")
		)
		(pad "36" smd rect
			(at -0.64008 -2.899918)
			(size 0.2286 0.6096)
			(layers "F.Cu" "F.Mask" "F.Paste")
			(net "PVDD11_S3_P1_TEMP0")
		)
		(pad "37" smd rect
			(at -1.089914 -2.899918)
			(size 0.2286 0.6096)
			(layers "F.Cu" "F.Mask" "F.Paste")
			(net "PVDD11_S3_P1_LSET1")
		)
		(pad "38" smd rect
			(at -1.540002 -2.899918)
			(size 0.2286 0.6096)
			(layers "F.Cu" "F.Mask" "F.Paste")
			(net "PVDD11_S3_P1_IMON1")
		)
		(pad "39" smd rect
			(at -1.99009 -2.899918)
			(size 0.2286 0.6096)
			(layers "F.Cu" "F.Mask" "F.Paste")
			(net "PVDD11_S3_P1_VCCS")
		)
		(pad "40" smd rect
			(at -0.87503 -1.27508)
			(size 1.7526 1.9558)
			(layers "F.Cu" "F.Mask" "F.Paste")
			(net "GND")
		)
		(pad "41" smd rect
			(at -1.525016 0.249936 270)
			(size 0.3048 0.4572)
			(layers "F.Cu" "F.Mask" "F.Paste")
			(net "NC_PVDD11_S3_P1_GL2_1")
		)
		(zone
			(layer "F.Cu")
			(hatch none 0.5)
			(connect_pads
				(clearance 0)
			)
			(min_thickness 0.25)
			(keepout
				(tracks not_allowed)
				(vias allowed)
				(pads allowed)
				(copperpour not_allowed)
				(footprints allowed)
			)
			(placement
				(enabled no)
				(sheetname "")
			)
			(fill
				(thermal_gap 0.5)
				(thermal_bridge_width 0.5)
				(island_removal_mode 0)
			)
			(polygon
				(pts
					(xy 180.419756 -348.751398) (xy 180.419756 -349.044768) (xy 185.42 -349.044768) (xy 185.42 -348.295468)
					(xy 185.129678 -348.295468) (xy 185.129678 -348.751144) (xy 180.710078 -348.751144) (xy 180.710078 -348.751398)
				)
			)
		)
		(zone
			(layer "F.Cu")
			(hatch none 0.5)
			(connect_pads
				(clearance 0)
			)
			(min_thickness 0.25)
			(keepout
				(tracks not_allowed)
				(vias allowed)
				(pads allowed)
				(copperpour not_allowed)
				(footprints allowed)
			)
			(placement
				(enabled no)
				(sheetname "")
			)
			(fill
				(thermal_gap 0.5)
				(thermal_bridge_width 0.5)
				(island_removal_mode 0)
			)
			(polygon
				(pts
					(xy 182.971948 -351.541842) (xy 182.971948 -353.599242) (xy 181.117748 -353.599242) (xy 181.117748 -353.358196)
					(xy 180.875432 -353.358196) (xy 180.875432 -353.83978) (xy 184.684924 -353.83978) (xy 184.684924 -353.654868)
					(xy 183.263286 -353.654868) (xy 183.263286 -351.495868) (xy 185.42 -351.495868) (xy 185.42 -351.246186)
					(xy 183.267604 -351.246186)
				)
			)
		)
	)
	(footprint ""
		(layer "F.Cu")
		(at 324.099174 -22.634956 -90)
		(property "Reference" "R5052"
			(at 0 0 270)
			(layer "F.SilkS")
			(hide yes)
			(effects
				(font
					(size 1.27 1.27)
				)
			)
		)
		(property "Value" ""
			(at 0 0 270)
			(layer "F.Fab")
			(effects
				(font
					(size 1.27 1.27)
				)
			)
		)
		(duplicate_pad_numbers_are_jumpers no)
		(fp_line
			(start -0.7874 0.4064)
			(end -0.7874 -0.4064)
			(stroke
				(width 0.1524)
				(type default)
			)
			(layer "F.SilkS")
		)
		(fp_line
			(start 0.7874 0.4064)
			(end -0.7874 0.4064)
			(stroke
				(width 0.1524)
				(type default)
			)
			(layer "F.SilkS")
		)
		(fp_line
			(start -0.7874 -0.4064)
			(end 0.7874 -0.4064)
			(stroke
				(width 0.1524)
				(type default)
			)
			(layer "F.SilkS")
		)
		(fp_line
			(start 0.7874 -0.4064)
			(end 0.7874 0.4064)
			(stroke
				(width 0.1524)
				(type default)
			)
			(layer "F.SilkS")
		)
		(fp_line
			(start -0.67945 0.3048)
			(end -0.67945 -0.305054)
			(stroke
				(width 0.1)
				(type default)
			)
			(layer "F.Fab")
		)
		(fp_line
			(start -0.12065 0.3048)
			(end -0.67945 0.3048)
			(stroke
				(width 0.1)
				(type default)
			)
			(layer "F.Fab")
		)
		(fp_line
			(start 0.120396 0.3048)
			(end 0.120396 0.2794)
			(stroke
				(width 0.1)
				(type default)
			)
			(layer "F.Fab")
		)
		(fp_line
			(start 0.67945 0.3048)
			(end 0.120396 0.3048)
			(stroke
				(width 0.1)
				(type default)
			)
			(layer "F.Fab")
		)
		(fp_line
			(start -0.12065 0.2794)
			(end -0.12065 0.3048)
			(stroke
				(width 0.1)
				(type default)
			)
			(layer "F.Fab")
		)
		(fp_line
			(start 0.120396 0.2794)
			(end -0.12065 0.2794)
			(stroke
				(width 0.1)
				(type default)
			)
			(layer "F.Fab")
		)
		(fp_line
			(start -0.12065 -0.2794)
			(end 0.12065 -0.2794)
			(stroke
				(width 0.1)
				(type default)
			)
			(layer "F.Fab")
		)
		(fp_line
			(start 0.12065 -0.2794)
			(end 0.12065 -0.3048)
			(stroke
				(width 0.1)
				(type default)
			)
			(layer "F.Fab")
		)
		(fp_line
			(start 0.12065 -0.3048)
			(end 0.67945 -0.3048)
			(stroke
				(width 0.1)
				(type default)
			)
			(layer "F.Fab")
		)
		(fp_line
			(start 0.67945 -0.3048)
			(end 0.67945 0.3048)
			(stroke
				(width 0.1)
				(type default)
			)
			(layer "F.Fab")
		)
		(fp_line
			(start -0.67945 -0.305054)
			(end -0.12065 -0.305054)
			(stroke
				(width 0.1)
				(type default)
			)
			(layer "F.Fab")
		)
		(fp_line
			(start -0.12065 -0.305054)
			(end -0.12065 -0.2794)
			(stroke
				(width 0.1)
				(type default)
			)
			(layer "F.Fab")
		)
		(pad "1" smd circle
			(at -0.40005 0 270)
			(size 0 0)
			(layers "F.Cu" "F.Mask" "F.Paste")
			(net "P3V3_RTC_AUX_R")
		)
		(pad "2" smd circle
			(at 0.40005 0 270)
			(size 0 0)
			(layers "F.Cu" "F.Mask" "F.Paste")
			(net "P3V3_RTC_AUX")
		)
	)
)
